(kicad_pcb
	(version 20260206)
	(generator "pcbnew")
	(generator_version "10.0")
	(general
		(thickness 1.6)
		(legacy_teardrops no)
	)
	(paper "A4")
	(title_block
		(title "ptb — 12523-1.1018WZS1506.brd")
		(comment 1 "Open Vault / Knox (Wiwynn) / footprints 1-3 of 61")
	)
	(layers
		(0 "F.Cu" signal "TOP")
		(4 "In1.Cu" signal "L2GND")
		(6 "In2.Cu" signal "L3VCC")
		(2 "B.Cu" signal "BOTTOM")
		(9 "F.Adhes" user "F.Adhesive")
		(11 "B.Adhes" user "B.Adhesive")
		(13 "F.Paste" user "Package Geometry/Pastemask Top")
		(15 "B.Paste" user "Package Geometry/Pastemask Bottom")
		(5 "F.SilkS" user "Ref Des/Silkscreen Top")
		(7 "B.SilkS" user "Ref Des/Silkscreen Bottom")
		(1 "F.Mask" user "Board Geometry/Soldermask Top")
		(3 "B.Mask" user "Board Geometry/Soldermask Bottom")
		(17 "Dwgs.User" user "User.Drawings")
		(19 "Cmts.User" user "User.Comments")
		(21 "Eco1.User" user "User.Eco1")
		(23 "Eco2.User" user "User.Eco2")
		(25 "Edge.Cuts" user "Board Geometry/Outline")
		(27 "Margin" user)
		(31 "F.CrtYd" user "Package Geometry/Place Bound Top")
		(29 "B.CrtYd" user "Package Geometry/Place Bound Bottom")
		(35 "F.Fab" user "Ref Des/Assembly Top")
		(33 "B.Fab" user "Ref Des/Assembly Bottom")
	)
	(footprint ""
		(layer "F.Cu")
		(at 147.169378 -16.997172 -90)
		(property "Reference" "R390"
			(at 0 0 270)
			(layer "F.SilkS")
			(hide yes)
			(effects
				(font
					(size 1.27 1.27)
				)
			)
		)
		(property "Value" "0R2J-2-GP"
			(at 0.064008 -3.993896 270)
			(unlocked yes)
			(layer "F.Fab")
			(hide yes)
			(effects
				(font
					(size 1.016 1.016)
					(thickness 0.1524)
				)
			)
		)
		(property "Device Type" "R402H16"
			(at 0.064008 -5.517896 270)
			(unlocked yes)
			(layer "F.Fab")
			(hide yes)
			(effects
				(font
					(size 1.016 1.016)
					(thickness 0.1524)
				)
			)
		)
		(duplicate_pad_numbers_are_jumpers no)
		(fp_line
			(start -0.508 -0.9398)
			(end -0.508 0.9398)
			(stroke
				(width 0.1524)
				(type default)
			)
			(layer "F.SilkS")
		)
		(fp_line
			(start 0.508 -0.9398)
			(end -0.508 -0.9398)
			(stroke
				(width 0.1524)
				(type default)
			)
			(layer "F.SilkS")
		)
		(fp_rect
			(start -0.508 0.9398)
			(end 0.508 -0.9398)
			(stroke
				(width 0)
				(type default)
			)
			(fill no)
			(layer "F.CrtYd")
		)
		(fp_rect
			(start -0.508 0.9398)
			(end 0.508 -0.9398)
			(stroke
				(width 0)
				(type default)
			)
			(fill no)
			(layer "F.Fab")
		)
		(pad "1" smd custom
			(at 0 -0.4445 270)
			(size 0.1397 0.1397)
			(layers "F.Cu" "F.Mask" "F.Paste")
			(net "TPS2490_DISABLE")
			(options
				(clearance outline)
				(anchor circle)
			)
			(primitives
				(gr_poly
					(pts
						(arc
							(start -0.1778 -0.2794)
							(mid -0.249642 -0.249642)
							(end -0.2794 -0.1778)
						)
						(arc
							(start -0.2794 0.1778)
							(mid -0.249642 0.249642)
							(end -0.1778 0.2794)
						)
						(arc
							(start 0.1778 0.2794)
							(mid 0.249642 0.249642)
							(end 0.2794 0.1778)
						)
						(arc
							(start 0.2794 -0.1778)
							(mid 0.249642 -0.249642)
							(end 0.1778 -0.2794)
						)
					)
					(width 0)
					(fill yes)
				)
			)
		)
		(pad "2" smd custom
			(at 0 0.4445 270)
			(size 0.1397 0.1397)
			(layers "F.Cu" "F.Mask" "F.Paste")
			(net "GND")
			(options
				(clearance outline)
				(anchor circle)
			)
			(primitives
				(gr_poly
					(pts
						(arc
							(start -0.1778 -0.2794)
							(mid -0.249642 -0.249642)
							(end -0.2794 -0.1778)
						)
						(arc
							(start -0.2794 0.1778)
							(mid -0.249642 0.249642)
							(end -0.1778 0.2794)
						)
						(arc
							(start 0.1778 0.2794)
							(mid 0.249642 0.249642)
							(end 0.2794 0.1778)
						)
						(arc
							(start 0.2794 -0.1778)
							(mid 0.249642 -0.249642)
							(end 0.1778 -0.2794)
						)
					)
					(width 0)
					(fill yes)
				)
			)
		)
	)
	(footprint ""
		(layer "F.Cu")
		(at -9.50087 -74.529188 -90)
		(property "Reference" "GF1"
			(at 0 0 270)
			(layer "F.SilkS")
			(hide yes)
			(effects
				(font
					(size 1.27 1.27)
				)
			)
		)
		(property "Value" "GF-36P-24P-GP"
			(at -19.5834 -9.482582 270)
			(unlocked yes)
			(layer "F.Fab")
			(hide yes)
			(effects
				(font
					(size 1.016 1.016)
					(thickness 0.1524)
				)
			)
		)
		(property "Device Type" "GF-36P-24P"
			(at -19.5834 -11.006582 270)
			(unlocked yes)
			(layer "F.Fab")
			(hide yes)
			(effects
				(font
					(size 1.016 1.016)
					(thickness 0.1524)
				)
			)
		)
		(duplicate_pad_numbers_are_jumpers no)
		(fp_rect
			(start -18.6436 2.032)
			(end 47.3964 -8.3312)
			(stroke
				(width 0)
				(type default)
			)
			(fill no)
			(layer "B.CrtYd")
		)
		(fp_rect
			(start -18.6436 2.032)
			(end 47.3964 -8.3312)
			(stroke
				(width 0)
				(type default)
			)
			(fill no)
			(layer "F.CrtYd")
		)
		(fp_rect
			(start -18.6436 2.032)
			(end 47.3964 -8.3312)
			(stroke
				(width 0)
				(type default)
			)
			(fill no)
			(layer "B.Fab")
		)
		(fp_rect
			(start -18.6436 2.032)
			(end 47.3964 -8.3312)
			(stroke
				(width 0)
				(type default)
			)
			(fill no)
			(layer "F.Fab")
		)
		(fp_text user "02 Do not mirror"
			(at 5.969 3.437636 270)
			(unlocked yes)
			(layer "F.Fab")
			(effects
				(font
					(size 1.016 1.016)
					(thickness 0.1524)
				)
				(justify left)
			)
		)
		(pad "P1" smd rect
			(at 40.64 -3.5306 270)
			(size 9.4488 6.2992)
			(drill
				(offset 0 0.381)
			)
			(layers "F.Cu" "F.Mask" "F.Paste")
			(net "P12V")
		)
		(pad "P2" smd rect
			(at 38.2778 -3.9116 270)
			(size 0.0254 0.0254)
			(layers "F.Cu" "F.Mask" "F.Paste")
			(net "P12V")
		)
		(pad "P3" smd rect
			(at 40.64 -3.9116 270)
			(size 0.0254 0.0254)
			(layers "F.Cu" "F.Mask" "F.Paste")
			(net "P12V")
		)
		(pad "P4" smd rect
			(at 43.0022 -3.9116 270)
			(size 0.0254 0.0254)
			(layers "F.Cu" "F.Mask" "F.Paste")
			(net "P12V")
		)
		(pad "P5" smd rect
			(at 30.48 -3.5306 270)
			(size 9.4488 6.2992)
			(drill
				(offset 0 0.381)
			)
			(layers "F.Cu" "F.Mask" "F.Paste")
			(net "P12V")
		)
		(pad "P6" smd rect
			(at 28.1178 -3.9116 270)
			(size 0.0254 0.0254)
			(layers "F.Cu" "F.Mask" "F.Paste")
			(net "P12V")
		)
		(pad "P7" smd rect
			(at 30.48 -3.9116 270)
			(size 0.0254 0.0254)
			(layers "F.Cu" "F.Mask" "F.Paste")
			(net "P12V")
		)
		(pad "P8" smd rect
			(at 32.8422 -3.9116 270)
			(size 0.0254 0.0254)
			(layers "F.Cu" "F.Mask" "F.Paste")
			(net "P12V")
		)
		(pad "P9" smd rect
			(at 20.32 -3.5306 270)
			(size 9.4488 6.2992)
			(drill
				(offset 0 0.381)
			)
			(layers "F.Cu" "F.Mask" "F.Paste")
			(net "GND")
		)
		(pad "P10" smd rect
			(at 17.9578 -3.9116 270)
			(size 0.0254 0.0254)
			(layers "F.Cu" "F.Mask" "F.Paste")
			(net "GND")
		)
		(pad "P11" smd rect
			(at 20.32 -3.9116 270)
			(size 0.0254 0.0254)
			(layers "F.Cu" "F.Mask" "F.Paste")
			(net "GND")
		)
		(pad "P12" smd rect
			(at 22.6822 -3.9116 270)
			(size 0.0254 0.0254)
			(layers "F.Cu" "F.Mask" "F.Paste")
			(net "GND")
		)
		(pad "P13" smd rect
			(at 10.16 -3.5306 270)
			(size 9.4488 6.2992)
			(drill
				(offset 0 0.381)
			)
			(layers "F.Cu" "F.Mask" "F.Paste")
			(net "GND")
		)
		(pad "P14" smd rect
			(at 7.7978 -3.9116 270)
			(size 0.0254 0.0254)
			(layers "F.Cu" "F.Mask" "F.Paste")
			(net "GND")
		)
		(pad "P15" smd rect
			(at 10.16 -3.9116 270)
			(size 0.0254 0.0254)
			(layers "F.Cu" "F.Mask" "F.Paste")
			(net "GND")
		)
		(pad "P16" smd rect
			(at 12.5222 -3.9116 270)
			(size 0.0254 0.0254)
			(layers "F.Cu" "F.Mask" "F.Paste")
			(net "GND")
		)
		(pad "P17" smd rect
			(at 2.6289 -3.5306 270)
			(size 4.191 6.2992)
			(drill
				(offset 0 0.381)
			)
			(layers "F.Cu" "F.Mask" "F.Paste")
			(net "GND")
		)
		(pad "P18" smd rect
			(at 2.6289 -3.9116 270)
			(size 0.0254 0.0254)
			(layers "F.Cu" "F.Mask" "F.Paste")
			(net "GND")
		)
		(pad "P19" smd rect
			(at 2.6289 -3.1496 270)
			(size 4.191 6.2992)
			(layers "F.Cu" "F.Mask" "F.Paste")
			(net "GND")
		)
		(pad "P20" smd rect
			(at 2.6289 -2.7686 270)
			(size 0.0254 0.0254)
			(layers "F.Cu" "F.Mask" "F.Paste")
			(net "GND")
		)
		(pad "P21" smd rect
			(at 10.16 -3.1496 270)
			(size 9.4488 6.2992)
			(layers "F.Cu" "F.Mask" "F.Paste")
			(net "GND")
		)
		(pad "P22" smd rect
			(at 7.7978 -2.7686 270)
			(size 0.0254 0.0254)
			(layers "F.Cu" "F.Mask" "F.Paste")
			(net "GND")
		)
		(pad "P23" smd rect
			(at 10.16 -2.7686 270)
			(size 0.0254 0.0254)
			(layers "F.Cu" "F.Mask" "F.Paste")
			(net "GND")
		)
		(pad "P24" smd rect
			(at 12.5222 -2.7686 270)
			(size 0.0254 0.0254)
			(layers "F.Cu" "F.Mask" "F.Paste")
			(net "GND")
		)
		(pad "P25" smd rect
			(at 20.32 -3.1496 270)
			(size 9.4488 6.2992)
			(layers "F.Cu" "F.Mask" "F.Paste")
			(net "GND")
		)
		(pad "P26" smd rect
			(at 17.9578 -2.7686 270)
			(size 0.0254 0.0254)
			(layers "F.Cu" "F.Mask" "F.Paste")
			(net "GND")
		)
		(pad "P27" smd rect
			(at 20.32 -2.7686 270)
			(size 0.0254 0.0254)
			(layers "F.Cu" "F.Mask" "F.Paste")
			(net "GND")
		)
		(pad "P28" smd rect
			(at 22.6822 -2.7686 270)
			(size 0.0254 0.0254)
			(layers "F.Cu" "F.Mask" "F.Paste")
			(net "GND")
		)
		(pad "P29" smd rect
			(at 30.48 -3.1496 270)
			(size 9.4488 6.2992)
			(layers "F.Cu" "F.Mask" "F.Paste")
			(net "P12V")
		)
		(pad "P30" smd rect
			(at 28.1178 -2.7686 270)
			(size 0.0254 0.0254)
			(layers "F.Cu" "F.Mask" "F.Paste")
			(net "P12V")
		)
		(pad "P31" smd rect
			(at 30.48 -2.7686 270)
			(size 0.0254 0.0254)
			(layers "F.Cu" "F.Mask" "F.Paste")
			(net "P12V")
		)
		(pad "P32" smd rect
			(at 32.8422 -2.7686 270)
			(size 0.0254 0.0254)
			(layers "F.Cu" "F.Mask" "F.Paste")
			(net "P12V")
		)
		(pad "P33" smd rect
			(at 40.64 -3.1496 270)
			(size 9.4488 6.2992)
			(layers "F.Cu" "F.Mask" "F.Paste")
			(net "P12V")
		)
		(pad "P34" smd rect
			(at 38.2778 -2.7686 270)
			(size 0.0254 0.0254)
			(layers "F.Cu" "F.Mask" "F.Paste")
			(net "P12V")
		)
		(pad "P35" smd rect
			(at 40.64 -2.7686 270)
			(size 0.0254 0.0254)
			(layers "F.Cu" "F.Mask" "F.Paste")
			(net "P12V")
		)
		(pad "P36" smd rect
			(at 43.0022 -2.7686 270)
			(size 0.0254 0.0254)
			(layers "F.Cu" "F.Mask" "F.Paste")
			(net "P12V")
		)
		(pad "S1" smd rect
			(at -2.23012 -2.8829 270)
			(size 0.8128 5.0038)
			(drill
				(offset 0 0.381)
			)
			(layers "F.Cu" "F.Mask" "F.Paste")
			(net "GND")
		)
		(pad "S2" smd rect
			(at -3.50012 -2.8829 270)
			(size 0.8128 5.0038)
			(drill
				(offset 0 0.381)
			)
			(layers "F.Cu" "F.Mask" "F.Paste")
			(net "P3V3")
		)
		(pad "S3" smd rect
			(at -4.77012 -2.8829 270)
			(size 0.8128 5.0038)
			(drill
				(offset 0 0.381)
			)
			(layers "F.Cu" "F.Mask" "F.Paste")
			(net "P3V3")
		)
		(pad "S4" smd rect
			(at -6.04012 -2.8829 270)
			(size 0.8128 5.0038)
			(drill
				(offset 0 0.381)
			)
			(layers "F.Cu" "F.Mask" "F.Paste")
			(net "PEER_TRAY_PRESENT")
		)
		(pad "S5" smd rect
			(at -7.31012 -2.8829 270)
			(size 0.8128 5.0038)
			(drill
				(offset 0 0.381)
			)
			(layers "F.Cu" "F.Mask" "F.Paste")
			(net "PWM_EXP_B")
		)
		(pad "S6" smd rect
			(at -8.58012 -2.8829 270)
			(size 0.8128 5.0038)
			(drill
				(offset 0 0.381)
			)
			(layers "F.Cu" "F.Mask" "F.Paste")
			(net "SELF_TRAY_PRESENT")
		)
		(pad "S7" smd rect
			(at -9.85012 -2.8829 270)
			(size 0.8128 5.0038)
			(drill
				(offset 0 0.381)
			)
			(layers "F.Cu" "F.Mask" "F.Paste")
			(net "PWM_EXP_A")
		)
		(pad "S8" smd rect
			(at -11.12012 -2.8829 270)
			(size 0.8128 5.0038)
			(drill
				(offset 0 0.381)
			)
			(layers "F.Cu" "F.Mask" "F.Paste")
			(net "GND")
		)
		(pad "S9" smd rect
			(at -12.39012 -2.8829 270)
			(size 0.8128 5.0038)
			(drill
				(offset 0 0.381)
			)
			(layers "F.Cu" "F.Mask" "F.Paste")
			(net "STRADDLE_I2C_C_SDA")
		)
		(pad "S10" smd rect
			(at -13.66012 -2.8829 270)
			(size 0.8128 5.0038)
			(drill
				(offset 0 0.381)
			)
			(layers "F.Cu" "F.Mask" "F.Paste")
			(net "GND")
		)
		(pad "S11" smd rect
			(at -14.93012 -2.8829 270)
			(size 0.8128 5.0038)
			(drill
				(offset 0 0.381)
			)
			(layers "F.Cu" "F.Mask" "F.Paste")
			(net "STRADDLE_I2C_C_SCL")
		)
		(pad "S12" smd rect
			(at -16.20012 -2.8829 270)
			(size 0.8128 5.0038)
			(drill
				(offset 0 0.381)
			)
			(layers "F.Cu" "F.Mask" "F.Paste")
			(net "GND")
		)
		(pad "S13" smd rect
			(at -16.20012 -2.5019 270)
			(size 0.8128 5.0038)
			(layers "F.Cu" "F.Mask" "F.Paste")
			(net "GND")
		)
		(pad "S14" smd rect
			(at -14.93012 -2.5019 270)
			(size 0.8128 5.0038)
			(layers "F.Cu" "F.Mask" "F.Paste")
			(net "SELF_1A&2A_HB")
		)
		(pad "S15" smd rect
			(at -13.66012 -2.5019 270)
			(size 0.8128 5.0038)
			(layers "F.Cu" "F.Mask" "F.Paste")
			(net "SELF_1B&2B_HB")
		)
		(pad "S16" smd rect
			(at -12.39012 -2.5019 270)
			(size 0.8128 5.0038)
			(layers "F.Cu" "F.Mask" "F.Paste")
			(net "TRAY_ID")
		)
		(pad "S17" smd rect
			(at -11.12012 -2.5019 270)
			(size 0.8128 5.0038)
			(layers "F.Cu" "F.Mask" "F.Paste")
			(net "FCB_HW_REV")
		)
		(pad "S18" smd rect
			(at -9.85012 -2.5019 270)
			(size 0.8128 5.0038)
			(layers "F.Cu" "F.Mask" "F.Paste")
			(net "SD_LATCH_RELEASE")
		)
		(pad "S19" smd rect
			(at -8.58012 -2.5019 270)
			(size 0.8128 5.0038)
			(layers "F.Cu" "F.Mask" "F.Paste")
			(net "GND")
		)
		(pad "S20" smd rect
			(at -7.31012 -2.5019 270)
			(size 0.8128 5.0038)
			(layers "F.Cu" "F.Mask" "F.Paste")
			(net "PEER_1A&2A_HB")
		)
		(pad "S21" smd rect
			(at -6.04012 -2.5019 270)
			(size 0.8128 5.0038)
			(layers "F.Cu" "F.Mask" "F.Paste")
			(net "PEER_1B&2B_HB")
		)
		(pad "S22" smd rect
			(at -4.77012 -2.5019 270)
			(size 0.8128 5.0038)
			(layers "F.Cu" "F.Mask" "F.Paste")
			(net "GND")
		)
		(pad "S23" smd rect
			(at -3.50012 -2.5019 270)
			(size 0.8128 5.0038)
			(layers "F.Cu" "F.Mask" "F.Paste")
			(net "GND")
		)
		(pad "S24" smd rect
			(at -2.23012 -2.5019 270)
			(size 0.8128 5.0038)
			(layers "F.Cu" "F.Mask" "F.Paste")
			(net "P5VA")
		)
		(zone
			(layer "F.Cu")
			(hatch none 0.5)
			(connect_pads
				(clearance 0)
			)
			(min_thickness 0.25)
			(keepout
				(tracks not_allowed)
				(vias allowed)
				(pads allowed)
				(copperpour not_allowed)
				(footprints allowed)
			)
			(placement
				(enabled no)
				(sheetname "")
			)
			(fill
				(thermal_gap 0.5)
				(thermal_bridge_width 0.5)
				(island_removal_mode 0)
			)
			(polygon
				(pts
					(xy -10.51687 -28.092908) (xy -9.50087 -28.092908) (xy -9.50087 -93.025468) (xy -10.51687 -93.025468)
				)
			)
		)
		(zone
			(layer "F.Cu")
			(hatch none 0.5)
			(connect_pads
				(clearance 0)
			)
			(min_thickness 0.25)
			(keepout
				(tracks allowed)
				(vias not_allowed)
				(pads allowed)
				(copperpour not_allowed)
				(footprints allowed)
			)
			(placement
				(enabled no)
				(sheetname "")
			)
			(fill
				(thermal_gap 0.5)
				(thermal_bridge_width 0.5)
				(island_removal_mode 0)
			)
			(polygon
				(pts
					(xy -10.51687 -28.092908) (xy -2.18567 -28.092908) (xy -2.18567 -93.025468) (xy -10.51687 -93.025468)
				)
			)
		)
		(zone
			(layer "B.Cu")
			(hatch none 0.5)
			(connect_pads
				(clearance 0)
			)
			(min_thickness 0.25)
			(keepout
				(tracks not_allowed)
				(vias allowed)
				(pads allowed)
				(copperpour not_allowed)
				(footprints allowed)
			)
			(placement
				(enabled no)
				(sheetname "")
			)
			(fill
				(thermal_gap 0.5)
				(thermal_bridge_width 0.5)
				(island_removal_mode 0)
			)
			(polygon
				(pts
					(xy -10.51687 -28.092908) (xy -9.50087 -28.092908) (xy -9.50087 -93.025468) (xy -10.51687 -93.025468)
				)
			)
		)
		(zone
			(layer "B.Cu")
			(hatch none 0.5)
			(connect_pads
				(clearance 0)
			)
			(min_thickness 0.25)
			(keepout
				(tracks allowed)
				(vias not_allowed)
				(pads allowed)
				(copperpour not_allowed)
				(footprints allowed)
			)
			(placement
				(enabled no)
				(sheetname "")
			)
			(fill
				(thermal_gap 0.5)
				(thermal_bridge_width 0.5)
				(island_removal_mode 0)
			)
			(polygon
				(pts
					(xy -10.51687 -28.092908) (xy -2.18567 -28.092908) (xy -2.18567 -93.025468) (xy -10.51687 -93.025468)
				)
			)
		)
	)
	(footprint ""
		(layer "F.Cu")
		(at 9.372092 -85.835744 90)
		(property "Reference" "R385"
			(at 0 0 90)
			(layer "F.SilkS")
			(hide yes)
			(effects
				(font
					(size 1.27 1.27)
				)
			)
		)
		(property "Value" "0R2J-2-GP"
			(at 0.064008 -3.993896 90)
			(unlocked yes)
			(layer "F.Fab")
			(hide yes)
			(effects
				(font
					(size 1.016 1.016)
					(thickness 0.1524)
				)
			)
		)
		(property "Device Type" "R402H16"
			(at 0.064008 -5.517896 90)
			(unlocked yes)
			(layer "F.Fab")
			(hide yes)
			(effects
				(font
					(size 1.016 1.016)
					(thickness 0.1524)
				)
			)
		)
		(duplicate_pad_numbers_are_jumpers no)
		(fp_line
			(start 0.508 -0.9398)
			(end -0.508 -0.9398)
			(stroke
				(width 0.1524)
				(type default)
			)
			(layer "F.SilkS")
		)
		(fp_line
			(start -0.508 -0.9398)
			(end -0.508 0.9398)
			(stroke
				(width 0.1524)
				(type default)
			)
			(layer "F.SilkS")
		)
		(fp_rect
			(start -0.508 0.9398)
			(end 0.508 -0.9398)
			(stroke
				(width 0)
				(type default)
			)
			(fill no)
			(layer "F.CrtYd")
		)
		(fp_rect
			(start -0.508 0.9398)
			(end 0.508 -0.9398)
			(stroke
				(width 0)
				(type default)
			)
			(fill no)
			(layer "F.Fab")
		)
		(pad "1" smd custom
			(at 0 -0.4445 90)
			(size 0.1397 0.1397)
			(layers "F.Cu" "F.Mask" "F.Paste")
			(net "PWM_EXP_B")
			(options
				(clearance outline)
				(anchor circle)
			)
			(primitives
				(gr_poly
					(pts
						(arc
							(start -0.1778 -0.2794)
							(mid -0.249642 -0.249642)
							(end -0.2794 -0.1778)
						)
						(arc
							(start -0.2794 0.1778)
							(mid -0.249642 0.249642)
							(end -0.1778 0.2794)
						)
						(arc
							(start 0.1778 0.2794)
							(mid 0.249642 0.249642)
							(end 0.2794 0.1778)
						)
						(arc
							(start 0.2794 -0.1778)
							(mid 0.249642 -0.249642)
							(end 0.1778 -0.2794)
						)
					)
					(width 0)
					(fill yes)
				)
			)
		)
		(pad "2" smd custom
			(at 0 0.4445 90)
			(size 0.1397 0.1397)
			(layers "F.Cu" "F.Mask" "F.Paste")
			(net "PWM_EXP_B_OUT")
			(options
				(clearance outline)
				(anchor circle)
			)
			(primitives
				(gr_poly
					(pts
						(arc
							(start -0.1778 -0.2794)
							(mid -0.249642 -0.249642)
							(end -0.2794 -0.1778)
						)
						(arc
							(start -0.2794 0.1778)
							(mid -0.249642 0.249642)
							(end -0.1778 0.2794)
						)
						(arc
							(start 0.1778 0.2794)
							(mid 0.249642 0.249642)
							(end 0.2794 0.1778)
						)
						(arc
							(start 0.2794 -0.1778)
							(mid 0.249642 -0.249642)
							(end 0.1778 -0.2794)
						)
					)
					(width 0)
					(fill yes)
				)
			)
		)
	)
)
